# T6G (Grand Teton) — schematic netlist excerpt (pin names and nets, part order shuffled) for the footprints in the layout excerpt that follows; sources: Cadence DE-HDL packaged netlist, KiCad conversion of 04192023_DAF0TMB3IC0_F0TG_MB_C_brd_V02_OCP.brd

PC178_4  Q_CAP  0.1UF 25V 10% X7R  pkg 0402  page 206 : A = SW_P12V_AUX_PVDDIO_P0_FLT ; B = GND
PC643  Q_CAP  470PF 50V 10% X7R  pkg 0402  page 224 : A = PVDD11_S3_P1_TEMP0 ; B = GND

(kicad_pcb
	(version 20260206)
	(generator "pcbnew")
	(generator_version "10.0")
	(general
		(thickness 1.6)
		(legacy_teardrops no)
	)
	(paper "A4")
	(title_block
		(title "04192023_DAF0TMB3IC0_F0TG_MB_C_brd_V02_OCP.brd")
		(comment 1 "Grand Teton / footprints 4550-4551 of 8354")
	)
	(layers
		(0 "F.Cu" signal "TOP")
		(4 "In1.Cu" signal "GND")
		(6 "In2.Cu" signal "IN1")
		(8 "In3.Cu" signal "GND1")
		(10 "In4.Cu" signal "IN2")
		(12 "In5.Cu" signal "GND2")
		(14 "In6.Cu" signal "IN3")
		(16 "In7.Cu" signal "GND3")
		(18 "In8.Cu" signal "VCC")
		(20 "In9.Cu" signal "VCC1")
		(22 "In10.Cu" signal "GND4")
		(24 "In11.Cu" signal "IN4")
		(26 "In12.Cu" signal "GND5")
		(28 "In13.Cu" signal "IN5")
		(30 "In14.Cu" signal "GND6")
		(32 "In15.Cu" signal "IN6")
		(34 "In16.Cu" signal "GND7")
		(2 "B.Cu" signal "BOTTOM")
		(9 "F.Adhes" user "F.Adhesive")
		(11 "B.Adhes" user "B.Adhesive")
		(13 "F.Paste" user "Package Geometry/Pastemask Top")
		(15 "B.Paste" user "Package Geometry/Pastemask Bottom")
		(5 "F.SilkS" user "Ref Des/Silkscreen Top")
		(7 "B.SilkS" user "Ref Des/Silkscreen Bottom")
		(1 "F.Mask" user "Board Geometry/Soldermask Top")
		(3 "B.Mask" user "Board Geometry/Soldermask Bottom")
		(17 "Dwgs.User" user "User.Drawings")
		(19 "Cmts.User" user "User.Comments")
		(21 "Eco1.User" user "User.Eco1")
		(23 "Eco2.User" user "User.Eco2")
		(25 "Edge.Cuts" user "Board Geometry/Outline")
		(27 "Margin" user)
		(31 "F.CrtYd" user "Package Geometry/Place Bound Top")
		(29 "B.CrtYd" user "Package Geometry/Place Bound Bottom")
		(35 "F.Fab" user "Ref Des/Assembly Top")
		(33 "B.Fab" user "Ref Des/Assembly Bottom")
	)
	(footprint ""
		(layer "F.Cu")
		(at 304.57521 -351.050352)
		(property "Reference" "PC178_4"
			(at 0 0 0)
			(layer "F.SilkS")
			(hide yes)
			(effects
				(font
					(size 1.27 1.27)
				)
			)
		)
		(property "Value" ""
			(at 0 0 0)
			(layer "F.Fab")
			(effects
				(font
					(size 1.27 1.27)
				)
			)
		)
		(duplicate_pad_numbers_are_jumpers no)
		(fp_line
			(start -0.7874 -0.4064)
			(end 0.7874 -0.4064)
			(stroke
				(width 0.1524)
				(type default)
			)
			(layer "F.SilkS")
		)
		(fp_line
			(start -0.7874 0.4064)
			(end -0.7874 -0.4064)
			(stroke
				(width 0.1524)
				(type default)
			)
			(layer "F.SilkS")
		)
		(fp_line
			(start 0.7874 -0.4064)
			(end 0.7874 0.4064)
			(stroke
				(width 0.1524)
				(type default)
			)
			(layer "F.SilkS")
		)
		(fp_line
			(start 0.7874 0.4064)
			(end -0.7874 0.4064)
			(stroke
				(width 0.1524)
				(type default)
			)
			(layer "F.SilkS")
		)
		(fp_line
			(start -0.67945 -0.305054)
			(end -0.12065 -0.305054)
			(stroke
				(width 0.1)
				(type default)
			)
			(layer "F.Fab")
		)
		(fp_line
			(start -0.67945 0.3048)
			(end -0.67945 -0.305054)
			(stroke
				(width 0.1)
				(type default)
			)
			(layer "F.Fab")
		)
		(fp_line
			(start -0.12065 -0.305054)
			(end -0.12065 -0.2794)
			(stroke
				(width 0.1)
				(type default)
			)
			(layer "F.Fab")
		)
		(fp_line
			(start -0.12065 -0.2794)
			(end 0.12065 -0.2794)
			(stroke
				(width 0.1)
				(type default)
			)
			(layer "F.Fab")
		)
		(fp_line
			(start -0.12065 0.2794)
			(end -0.12065 0.3048)
			(stroke
				(width 0.1)
				(type default)
			)
			(layer "F.Fab")
		)
		(fp_line
			(start -0.12065 0.3048)
			(end -0.67945 0.3048)
			(stroke
				(width 0.1)
				(type default)
			)
			(layer "F.Fab")
		)
		(fp_line
			(start 0.120396 0.2794)
			(end -0.12065 0.2794)
			(stroke
				(width 0.1)
				(type default)
			)
			(layer "F.Fab")
		)
		(fp_line
			(start 0.120396 0.3048)
			(end 0.120396 0.2794)
			(stroke
				(width 0.1)
				(type default)
			)
			(layer "F.Fab")
		)
		(fp_line
			(start 0.12065 -0.3048)
			(end 0.67945 -0.3048)
			(stroke
				(width 0.1)
				(type default)
			)
			(layer "F.Fab")
		)
		(fp_line
			(start 0.12065 -0.2794)
			(end 0.12065 -0.3048)
			(stroke
				(width 0.1)
				(type default)
			)
			(layer "F.Fab")
		)
		(fp_line
			(start 0.67945 -0.3048)
			(end 0.67945 0.3048)
			(stroke
				(width 0.1)
				(type default)
			)
			(layer "F.Fab")
		)
		(fp_line
			(start 0.67945 0.3048)
			(end 0.120396 0.3048)
			(stroke
				(width 0.1)
				(type default)
			)
			(layer "F.Fab")
		)
		(pad "1" smd circle
			(at -0.40005 0)
			(size 0 0)
			(layers "F.Cu" "F.Mask" "F.Paste")
			(net "SW_P12V_AUX_PVDDIO_P0_FLT")
		)
		(pad "2" smd circle
			(at 0.40005 0)
			(size 0 0)
			(layers "F.Cu" "F.Mask" "F.Paste")
			(net "GND")
		)
	)
	(footprint ""
		(layer "F.Cu")
		(at 166.937944 -348.284546)
		(property "Reference" "PC643"
			(at 0 0 0)
			(layer "F.SilkS")
			(hide yes)
			(effects
				(font
					(size 1.27 1.27)
				)
			)
		)
		(property "Value" ""
			(at 0 0 0)
			(layer "F.Fab")
			(effects
				(font
					(size 1.27 1.27)
				)
			)
		)
		(duplicate_pad_numbers_are_jumpers no)
		(fp_line
			(start -0.7874 -0.4064)
			(end 0.7874 -0.4064)
			(stroke
				(width 0.1524)
				(type default)
			)
			(layer "F.SilkS")
		)
		(fp_line
			(start -0.7874 0.4064)
			(end -0.7874 -0.4064)
			(stroke
				(width 0.1524)
				(type default)
			)
			(layer "F.SilkS")
		)
		(fp_line
			(start 0.7874 -0.4064)
			(end 0.7874 0.4064)
			(stroke
				(width 0.1524)
				(type default)
			)
			(layer "F.SilkS")
		)
		(fp_line
			(start 0.7874 0.4064)
			(end -0.7874 0.4064)
			(stroke
				(width 0.1524)
				(type default)
			)
			(layer "F.SilkS")
		)
		(fp_line
			(start -0.67945 -0.305054)
			(end -0.12065 -0.305054)
			(stroke
				(width 0.1)
				(type default)
			)
			(layer "F.Fab")
		)
		(fp_line
			(start -0.67945 0.3048)
			(end -0.67945 -0.305054)
			(stroke
				(width 0.1)
				(type default)
			)
			(layer "F.Fab")
		)
		(fp_line
			(start -0.12065 -0.305054)
			(end -0.12065 -0.2794)
			(stroke
				(width 0.1)
				(type default)
			)
			(layer "F.Fab")
		)
		(fp_line
			(start -0.12065 -0.2794)
			(end 0.12065 -0.2794)
			(stroke
				(width 0.1)
				(type default)
			)
			(layer "F.Fab")
		)
		(fp_line
			(start -0.12065 0.2794)
			(end -0.12065 0.3048)
			(stroke
				(width 0.1)
				(type default)
			)
			(layer "F.Fab")
		)
		(fp_line
			(start -0.12065 0.3048)
			(end -0.67945 0.3048)
			(stroke
				(width 0.1)
				(type default)
			)
			(layer "F.Fab")
		)
		(fp_line
			(start 0.120396 0.2794)
			(end -0.12065 0.2794)
			(stroke
				(width 0.1)
				(type default)
			)
			(layer "F.Fab")
		)
		(fp_line
			(start 0.120396 0.3048)
			(end 0.120396 0.2794)
			(stroke
				(width 0.1)
				(type default)
			)
			(layer "F.Fab")
		)
		(fp_line
			(start 0.12065 -0.3048)
			(end 0.67945 -0.3048)
			(stroke
				(width 0.1)
				(type default)
			)
			(layer "F.Fab")
		)
		(fp_line
			(start 0.12065 -0.2794)
			(end 0.12065 -0.3048)
			(stroke
				(width 0.1)
				(type default)
			)
			(layer "F.Fab")
		)
		(fp_line
			(start 0.67945 -0.3048)
			(end 0.67945 0.3048)
			(stroke
				(width 0.1)
				(type default)
			)
			(layer "F.Fab")
		)
		(fp_line
			(start 0.67945 0.3048)
			(end 0.120396 0.3048)
			(stroke
				(width 0.1)
				(type default)
			)
			(layer "F.Fab")
		)
		(pad "1" smd circle
			(at -0.40005 0)
			(size 0 0)
			(layers "F.Cu" "F.Mask" "F.Paste")
			(net "PVDD11_S3_P1_TEMP0")
		)
		(pad "2" smd circle
			(at 0.40005 0)
			(size 0 0)
			(layers "F.Cu" "F.Mask" "F.Paste")
			(net "GND")
		)
	)
)
